# BASEBOARD_FAB2 (Tioga Pass) — schematic netlist excerpt (pin names and nets, part order shuffled) for the footprints in the layout excerpt that follows; sources: Cadence DE-HDL packaged netlist, KiCad conversion of Wiwynn_Tioga_Pass_MB.brd

R25W161  RES  1.00K 1% CHIP  pkg 0402  page 254 : A = P3V3_STBY ; B = JTAG_BMC_BUF_TMS
C4D30  CAP  1.0UF 16V 10% X6S  pkg 0402  page 203 : A = VR_FET_SW_P12V_STBY_PVCCIN_CPU0 ; B = GND

(kicad_pcb
	(version 20260206)
	(generator "pcbnew")
	(generator_version "10.0")
	(general
		(thickness 1.6)
		(legacy_teardrops no)
	)
	(paper "A4")
	(title_block
		(title "Wiwynn_Tioga_Pass_MB.brd")
		(comment 1 "Tioga Pass / footprints 2228-2229 of 4770")
	)
	(layers
		(0 "F.Cu" signal "TOP")
		(4 "In1.Cu" signal "L2GND")
		(6 "In2.Cu" signal "L3")
		(8 "In3.Cu" signal "L4GND")
		(10 "In4.Cu" signal "L5")
		(12 "In5.Cu" signal "L6GND")
		(14 "In6.Cu" signal "L7VCC")
		(16 "In7.Cu" signal "L8VCC")
		(18 "In8.Cu" signal "L9GND")
		(20 "In9.Cu" signal "L10")
		(22 "In10.Cu" signal "L11GND")
		(24 "In11.Cu" signal "L12")
		(26 "In12.Cu" signal "L13GND")
		(2 "B.Cu" signal "BOTTOM")
		(9 "F.Adhes" user "F.Adhesive")
		(11 "B.Adhes" user "B.Adhesive")
		(13 "F.Paste" user "Package Geometry/Pastemask Top")
		(15 "B.Paste" user "Package Geometry/Pastemask Bottom")
		(5 "F.SilkS" user "Ref Des/Silkscreen Top")
		(7 "B.SilkS" user "Ref Des/Silkscreen Bottom")
		(1 "F.Mask" user "Board Geometry/Soldermask Top")
		(3 "B.Mask" user "Board Geometry/Soldermask Bottom")
		(17 "Dwgs.User" user "User.Drawings")
		(19 "Cmts.User" user "User.Comments")
		(21 "Eco1.User" user "User.Eco1")
		(23 "Eco2.User" user "User.Eco2")
		(25 "Edge.Cuts" user "Board Geometry/Outline")
		(27 "Margin" user)
		(31 "F.CrtYd" user "Package Geometry/Place Bound Top")
		(29 "B.CrtYd" user "Package Geometry/Place Bound Bottom")
		(35 "F.Fab" user "Ref Des/Assembly Top")
		(33 "B.Fab" user "Ref Des/Assembly Bottom")
	)
	(footprint ""
		(layer "F.Cu")
		(at 194.749928 -75.954382 -90)
		(property "Reference" "C4D30"
			(at 0 0 270)
			(layer "F.SilkS")
			(hide yes)
			(effects
				(font
					(size 1.27 1.27)
				)
			)
		)
		(property "Value" ""
			(at 0 0 270)
			(layer "F.Fab")
			(effects
				(font
					(size 1.27 1.27)
				)
			)
		)
		(duplicate_pad_numbers_are_jumpers no)
		(fp_poly
			(pts
				(xy 0.3048 -0.1016) (xy 0.3048 0.9906) (xy -0.3048 0.9906) (xy -0.3048 -0.1016)
			)
			(stroke
				(width 0)
				(type default)
			)
			(fill no)
			(layer "F.CrtYd")
		)
		(fp_line
			(start -0.3048 0.9906)
			(end 0.3048 0.9906)
			(stroke
				(width 0.1)
				(type default)
			)
			(layer "F.Fab")
		)
		(fp_line
			(start 0.3048 0.9906)
			(end 0.3048 -0.1016)
			(stroke
				(width 0.1)
				(type default)
			)
			(layer "F.Fab")
		)
		(fp_line
			(start -0.3048 -0.1016)
			(end -0.3048 0.9906)
			(stroke
				(width 0.1)
				(type default)
			)
			(layer "F.Fab")
		)
		(fp_line
			(start 0.3048 -0.1016)
			(end -0.3048 -0.1016)
			(stroke
				(width 0.1)
				(type default)
			)
			(layer "F.Fab")
		)
		(pad "1" smd rect
			(at 0 0 270)
			(size 0.508 0.508)
			(layers "F.Cu" "F.Mask" "F.Paste")
			(net "VR_FET_SW_P12V_STBY_PVCCIN_CPU0")
		)
		(pad "2" smd rect
			(at 0 0.889 270)
			(size 0.508 0.508)
			(layers "F.Cu" "F.Mask" "F.Paste")
			(net "GND")
		)
		(zone
			(layer "F.Cu")
			(hatch none 0.5)
			(connect_pads
				(clearance 0)
			)
			(min_thickness 0.25)
			(keepout
				(tracks not_allowed)
				(vias allowed)
				(pads allowed)
				(copperpour not_allowed)
				(footprints allowed)
			)
			(placement
				(enabled no)
				(sheetname "")
			)
			(fill
				(thermal_gap 0.5)
				(thermal_bridge_width 0.5)
				(island_removal_mode 0)
			)
			(polygon
				(pts
					(xy 194.114928 -76.208382) (xy 194.114928 -75.700382) (xy 194.495928 -75.700382) (xy 194.495928 -76.208382)
				)
			)
		)
		(zone
			(layer "F.Cu")
			(hatch none 0.5)
			(connect_pads
				(clearance 0)
			)
			(min_thickness 0.25)
			(keepout
				(tracks allowed)
				(vias not_allowed)
				(pads allowed)
				(copperpour not_allowed)
				(footprints allowed)
			)
			(placement
				(enabled no)
				(sheetname "")
			)
			(fill
				(thermal_gap 0.5)
				(thermal_bridge_width 0.5)
				(island_removal_mode 0)
			)
			(polygon
				(pts
					(xy 194.495928 -76.208382) (xy 194.495928 -75.700382) (xy 194.114928 -75.700382) (xy 194.114928 -76.208382)
				)
			)
		)
	)
	(footprint ""
		(layer "F.Cu")
		(at 440.817 -143.764 90)
		(property "Reference" "R25W161"
			(at -0.8382 -0.67818 90)
			(unlocked yes)
			(layer "F.SilkS")
			(effects
				(font
					(size 0.4064 0.254)
					(thickness 0.1524)
				)
				(justify left)
			)
		)
		(property "Value" ""
			(at 0 0 90)
			(layer "F.Fab")
			(effects
				(font
					(size 1.27 1.27)
				)
			)
		)
		(duplicate_pad_numbers_are_jumpers no)
		(fp_poly
			(pts
				(xy -0.2794 -0.1016) (xy 0.2794 -0.1016) (xy 0.2794 0.9906) (xy -0.2794 0.9906)
			)
			(stroke
				(width 0)
				(type default)
			)
			(fill no)
			(layer "F.CrtYd")
		)
		(fp_line
			(start 0.2794 -0.1016)
			(end -0.2794 -0.1016)
			(stroke
				(width 0.1)
				(type default)
			)
			(layer "F.Fab")
		)
		(fp_line
			(start -0.2794 -0.1016)
			(end -0.2794 0.9906)
			(stroke
				(width 0.1)
				(type default)
			)
			(layer "F.Fab")
		)
		(fp_line
			(start 0.2794 0.9906)
			(end 0.2794 -0.1016)
			(stroke
				(width 0.1)
				(type default)
			)
			(layer "F.Fab")
		)
		(fp_line
			(start -0.2794 0.9906)
			(end 0.2794 0.9906)
			(stroke
				(width 0.1)
				(type default)
			)
			(layer "F.Fab")
		)
		(pad "1" smd rect
			(at 0 0 90)
			(size 0.508 0.508)
			(layers "F.Cu" "F.Mask" "F.Paste")
			(net "P3V3_STBY")
		)
		(pad "2" smd rect
			(at 0 0.889 90)
			(size 0.508 0.508)
			(layers "F.Cu" "F.Mask" "F.Paste")
			(net "JTAG_BMC_BUF_TMS")
		)
		(zone
			(layer "F.Cu")
			(hatch none 0.5)
			(connect_pads
				(clearance 0)
			)
			(min_thickness 0.25)
			(keepout
				(tracks allowed)
				(vias not_allowed)
				(pads allowed)
				(copperpour not_allowed)
				(footprints allowed)
			)
			(placement
				(enabled no)
				(sheetname "")
			)
			(fill
				(thermal_gap 0.5)
				(thermal_bridge_width 0.5)
				(island_removal_mode 0)
			)
			(polygon
				(pts
					(xy 441.071 -143.51) (xy 441.071 -144.018) (xy 441.452 -144.018) (xy 441.452 -143.51)
				)
			)
		)
		(zone
			(layer "F.Cu")
			(hatch none 0.5)
			(connect_pads
				(clearance 0)
			)
			(min_thickness 0.25)
			(keepout
				(tracks not_allowed)
				(vias allowed)
				(pads allowed)
				(copperpour not_allowed)
				(footprints allowed)
			)
			(placement
				(enabled no)
				(sheetname "")
			)
			(fill
				(thermal_gap 0.5)
				(thermal_bridge_width 0.5)
				(island_removal_mode 0)
			)
			(polygon
				(pts
					(xy 441.452 -143.51) (xy 441.452 -144.018) (xy 441.071 -144.018) (xy 441.071 -143.51)
				)
			)
		)
	)
)
